(kicad_pcb
	(version 20240108)
	(generator "pcbnew")
	(generator_version "8.0")
	(general
		(thickness 1.62)
		(legacy_teardrops no)
	)
	(paper "A4")
	(title_block
		(title "Jetson Orin Baseboard")
		(date "2025-03-12")
		(rev "1.3.4")
		(company "Antmicro Ltd")
		(comment 1 "www.antmicro.com")
		(comment 9 "footprints 560-564 of 677")
	)
	(layers
		(0 "F.Cu" signal)
		(1 "In1.Cu" signal)
		(2 "In2.Cu" signal)
		(3 "In3.Cu" signal)
		(4 "In4.Cu" jumper)
		(5 "In5.Cu" signal)
		(6 "In6.Cu" signal)
		(31 "B.Cu" signal)
		(32 "B.Adhes" user "B.Adhesive")
		(33 "F.Adhes" user "F.Adhesive")
		(34 "B.Paste" user)
		(35 "F.Paste" user)
		(36 "B.SilkS" user "B.Silkscreen")
		(37 "F.SilkS" user "F.Silkscreen")
		(38 "B.Mask" user)
		(39 "F.Mask" user)
		(40 "Dwgs.User" user "User.Drawings")
		(41 "Cmts.User" user "User.Comments")
		(42 "Eco1.User" user "User.Eco1")
		(43 "Eco2.User" user "User.Eco2")
		(44 "Edge.Cuts" user)
		(45 "Margin" user)
		(46 "B.CrtYd" user "B.Courtyard")
		(47 "F.CrtYd" user "F.Courtyard")
		(48 "B.Fab" user)
		(49 "F.Fab" user)
	)
	(footprint "antmicro-footprints:R_0402_1005Metric"
		(layer "B.Cu")
		(at 95.975 87.15)
		(descr "Resistor SMD 0402")
		(tags "resistor SMD 0402")
		(property "Reference" "R160"
			(at 3.765 0.43 180)
			(layer "B.SilkS")
			(effects
				(font
					(size 0.7 0.7)
					(thickness 0.15)
				)
				(justify left bottom mirror)
			)
		)
		(property "Value" "R_10k_0402"
			(at 0 -1.4 180)
			(layer "B.Fab")
			(effects
				(font
					(size 0.7 0.7)
					(thickness 0.15)
				)
				(justify left bottom mirror)
			)
		)
		(property "Footprint" "antmicro-footprints:R_0402_1005Metric"
			(at 0 0 0)
			(layer "F.Fab")
			(hide yes)
			(effects
				(font
					(size 1.27 1.27)
					(thickness 0.15)
				)
			)
		)
		(property "Datasheet" "https://www.bourns.com/docs/product-datasheets/cr.pdf"
			(at 0 0 0)
			(layer "F.Fab")
			(hide yes)
			(effects
				(font
					(size 1.27 1.27)
					(thickness 0.15)
				)
			)
		)
		(property "Author" "Antmicro"
			(at 0 0 0)
			(layer "B.Fab")
			(hide yes)
			(effects
				(font
					(size 1 1)
					(thickness 0.15)
				)
				(justify mirror)
			)
		)
		(property "License" "Apache-2.0"
			(at 0 0 0)
			(layer "B.Fab")
			(hide yes)
			(effects
				(font
					(size 1 1)
					(thickness 0.15)
				)
				(justify mirror)
			)
		)
		(property "MPN" "CR0402-FX-1002GLF"
			(at 0 0 0)
			(layer "B.Fab")
			(hide yes)
			(effects
				(font
					(size 1 1)
					(thickness 0.15)
				)
				(justify mirror)
			)
		)
		(property "Manufacturer" "Bourns"
			(at 0 0 0)
			(layer "B.Fab")
			(hide yes)
			(effects
				(font
					(size 1 1)
					(thickness 0.15)
				)
				(justify mirror)
			)
		)
		(property "Tolerance" "1%"
			(at 0 0 0)
			(layer "B.Fab")
			(hide yes)
			(effects
				(font
					(size 1 1)
					(thickness 0.15)
				)
				(justify mirror)
			)
		)
		(property "Val" "10k"
			(at 0 0 0)
			(layer "B.Fab")
			(hide yes)
			(effects
				(font
					(size 1 1)
					(thickness 0.15)
				)
				(justify mirror)
			)
		)
		(sheetname "HDMI")
		(sheetfile "hdmi.kicad_sch")
		(attr smd)
		(fp_rect
			(start -0.925 0.47)
			(end 0.925 -0.47)
			(stroke
				(width 0.05)
				(type default)
			)
			(fill none)
			(layer "B.CrtYd")
		)
		(fp_rect
			(start -0.5 0.25)
			(end 0.5 -0.25)
			(stroke
				(width 0.15)
				(type solid)
			)
			(fill none)
			(layer "B.Fab")
		)
		(fp_text user "${REFERENCE}"
			(at -0.95 -3.168 180)
			(layer "B.Fab")
			(hide yes)
			(effects
				(font
					(size 0.7 0.7)
					(thickness 0.15)
				)
				(justify left bottom mirror)
			)
		)
		(fp_text user "License: Apache-2.0"
			(at -0.95 -5.169 180)
			(layer "B.Fab")
			(hide yes)
			(effects
				(font
					(size 0.7 0.7)
					(thickness 0.15)
				)
				(justify left bottom mirror)
			)
		)
		(fp_text user "Author: Antmicro"
			(at -0.95 -4.169 180)
			(layer "B.Fab")
			(hide yes)
			(effects
				(font
					(size 0.7 0.7)
					(thickness 0.15)
				)
				(justify left bottom mirror)
			)
		)
		(pad "1" smd roundrect
			(at -0.48 0)
			(size 0.59 0.64)
			(layers "B.Cu" "B.Paste" "B.Mask")
			(roundrect_rratio 0.25)
			(net 678 "/HDMI/DP_MUX_EN")
			(pintype "passive")
		)
		(pad "2" smd roundrect
			(at 0.48 0)
			(size 0.59 0.64)
			(layers "B.Cu" "B.Paste" "B.Mask")
			(roundrect_rratio 0.25)
			(net 87 "+3V3")
			(pintype "passive")
		)
	)
	(footprint "antmicro-footprints:FB_0805_2012Metric"
		(layer "B.Cu")
		(at 54.5 93.6875 90)
		(descr "FERRITE BEAD 0805")
		(tags "FERRITE BEAD 0805")
		(property "Reference" "FB2"
			(at 1.1175 1.77 -90)
			(layer "B.SilkS")
			(effects
				(font
					(size 0.7 0.7)
					(thickness 0.15)
				)
				(justify left bottom mirror)
			)
		)
		(property "Value" "FB_220Z_2A_Murata-BLM21PG_0805"
			(at 0 -1.8 -90)
			(layer "B.Fab")
			(effects
				(font
					(size 0.7 0.7)
					(thickness 0.15)
				)
				(justify left bottom mirror)
			)
		)
		(property "Footprint" "antmicro-footprints:FB_0805_2012Metric"
			(at 0 0 90)
			(layer "F.Fab")
			(hide yes)
			(effects
				(font
					(size 1.27 1.27)
					(thickness 0.15)
				)
			)
		)
		(property "Datasheet" "https://www.murata.com/products/productdata/8796738977822/ENFA0005.pdf?1653276712000"
			(at 0 0 90)
			(layer "F.Fab")
			(hide yes)
			(effects
				(font
					(size 1.27 1.27)
					(thickness 0.15)
				)
			)
		)
		(property "Author" "Antmicro"
			(at 148.1875 39.1875 0)
			(layer "B.Fab")
			(hide yes)
			(effects
				(font
					(size 1 1)
					(thickness 0.15)
				)
				(justify mirror)
			)
		)
		(property "Current" ""
			(at 148.1875 39.1875 0)
			(layer "B.Fab")
			(hide yes)
			(effects
				(font
					(size 1 1)
					(thickness 0.15)
				)
				(justify mirror)
			)
		)
		(property "License" "Apache-2.0"
			(at 148.1875 39.1875 0)
			(layer "B.Fab")
			(hide yes)
			(effects
				(font
					(size 1 1)
					(thickness 0.15)
				)
				(justify mirror)
			)
		)
		(property "MPN" "BLM21PG221SN1D"
			(at 148.1875 39.1875 0)
			(layer "B.Fab")
			(hide yes)
			(effects
				(font
					(size 1 1)
					(thickness 0.15)
				)
				(justify mirror)
			)
		)
		(property "Manufacturer" "Murata"
			(at 148.1875 39.1875 0)
			(layer "B.Fab")
			(hide yes)
			(effects
				(font
					(size 1 1)
					(thickness 0.15)
				)
				(justify mirror)
			)
		)
		(property "Val" "220Z/2A"
			(at 148.1875 39.1875 0)
			(layer "B.Fab")
			(hide yes)
			(effects
				(font
					(size 1 1)
					(thickness 0.15)
				)
				(justify mirror)
			)
		)
		(sheetname "Ethernet")
		(sheetfile "ethernet.kicad_sch")
		(attr smd)
		(fp_line
			(start 0.281 -0.698)
			(end -0.319 -0.698)
			(stroke
				(width 0.15)
				(type solid)
			)
			(layer "B.SilkS")
		)
		(fp_line
			(start 0.299 0.698)
			(end -0.299 0.698)
			(stroke
				(width 0.15)
				(type solid)
			)
			(layer "B.SilkS")
		)
		(fp_rect
			(start 1.95 0.9)
			(end -1.95 -0.9)
			(stroke
				(width 0.05)
				(type default)
			)
			(fill none)
			(layer "B.CrtYd")
		)
		(fp_line
			(start 0.948 -0.681)
			(end -0.948 -0.681)
			(stroke
				(width 0.15)
				(type solid)
			)
			(layer "B.Fab")
		)
		(fp_line
			(start 0.948 -0.676)
			(end 0.948 0.676)
			(stroke
				(width 0.15)
				(type solid)
			)
			(layer "B.Fab")
		)
		(fp_line
			(start -0.948 -0.676)
			(end -0.948 0.676)
			(stroke
				(width 0.15)
				(type solid)
			)
			(layer "B.Fab")
		)
		(fp_line
			(start 0.948 0.681)
			(end -0.948 0.681)
			(stroke
				(width 0.15)
				(type solid)
			)
			(layer "B.Fab")
		)
		(fp_text user "License: Apache-2.0"
			(at -1.9 -5.75 -90)
			(layer "B.Fab")
			(hide yes)
			(effects
				(font
					(size 0.7 0.7)
					(thickness 0.15)
				)
				(justify left bottom mirror)
			)
		)
		(fp_text user "Author: Antmicro"
			(at -1.9 -4.4 -90)
			(layer "B.Fab")
			(hide yes)
			(effects
				(font
					(size 0.7 0.7)
					(thickness 0.15)
				)
				(justify left bottom mirror)
			)
		)
		(fp_text user "${REFERENCE}"
			(at -1.9 -3.1 -90)
			(layer "B.Fab")
			(hide yes)
			(effects
				(font
					(size 0.7 0.7)
					(thickness 0.15)
				)
				(justify left bottom mirror)
			)
		)
		(pad "1" smd roundrect
			(at -1.1 0 90)
			(size 1.2 1.3)
			(layers "B.Cu" "B.Paste" "B.Mask")
			(roundrect_rratio 0.25)
			(net 149 "Net-(D12-Pad2)")
			(pintype "passive")
		)
		(pad "2" smd roundrect
			(at 1.1 0 90)
			(size 1.2 1.3)
			(layers "B.Cu" "B.Paste" "B.Mask")
			(roundrect_rratio 0.25)
			(net 105 "/Ethernet/VDD")
			(pintype "passive")
		)
	)
	(footprint "antmicro-footprints:R_0402_1005Metric"
		(layer "B.Cu")
		(at 49.975 116 180)
		(descr "Resistor SMD 0402")
		(tags "resistor SMD 0402")
		(property "Reference" "R46"
			(at 13.375 -9.296666 0)
			(layer "B.SilkS")
			(effects
				(font
					(size 0.7 0.7)
					(thickness 0.15)
				)
				(justify left bottom mirror)
			)
		)
		(property "Value" "R_10k_0402"
			(at 0 -1.4 0)
			(layer "B.Fab")
			(effects
				(font
					(size 0.7 0.7)
					(thickness 0.15)
				)
				(justify left bottom mirror)
			)
		)
		(property "Footprint" "antmicro-footprints:R_0402_1005Metric"
			(at 0 0 180)
			(layer "F.Fab")
			(hide yes)
			(effects
				(font
					(size 1.27 1.27)
					(thickness 0.15)
				)
			)
		)
		(property "Datasheet" "https://www.bourns.com/docs/product-datasheets/cr.pdf"
			(at 0 0 180)
			(layer "F.Fab")
			(hide yes)
			(effects
				(font
					(size 1.27 1.27)
					(thickness 0.15)
				)
			)
		)
		(property "Author" "Antmicro"
			(at 99.95 232 0)
			(layer "B.Fab")
			(hide yes)
			(effects
				(font
					(size 1 1)
					(thickness 0.15)
				)
				(justify mirror)
			)
		)
		(property "License" "Apache-2.0"
			(at 99.95 232 0)
			(layer "B.Fab")
			(hide yes)
			(effects
				(font
					(size 1 1)
					(thickness 0.15)
				)
				(justify mirror)
			)
		)
		(property "MPN" "CR0402-FX-1002GLF"
			(at 99.95 232 0)
			(layer "B.Fab")
			(hide yes)
			(effects
				(font
					(size 1 1)
					(thickness 0.15)
				)
				(justify mirror)
			)
		)
		(property "Manufacturer" "Bourns"
			(at 99.95 232 0)
			(layer "B.Fab")
			(hide yes)
			(effects
				(font
					(size 1 1)
					(thickness 0.15)
				)
				(justify mirror)
			)
		)
		(property "Tolerance" "1%"
			(at 99.95 232 0)
			(layer "B.Fab")
			(hide yes)
			(effects
				(font
					(size 1 1)
					(thickness 0.15)
				)
				(justify mirror)
			)
		)
		(property "Val" "10k"
			(at 99.95 232 0)
			(layer "B.Fab")
			(hide yes)
			(effects
				(font
					(size 1 1)
					(thickness 0.15)
				)
				(justify mirror)
			)
		)
		(sheetname "USB Debug, DP")
		(sheetfile "usb.kicad_sch")
		(attr smd)
		(fp_rect
			(start -0.925 0.47)
			(end 0.925 -0.47)
			(stroke
				(width 0.05)
				(type default)
			)
			(fill none)
			(layer "B.CrtYd")
		)
		(fp_rect
			(start -0.5 0.25)
			(end 0.5 -0.25)
			(stroke
				(width 0.15)
				(type solid)
			)
			(fill none)
			(layer "B.Fab")
		)
		(fp_text user "License: Apache-2.0"
			(at -0.95 -5.169 0)
			(layer "B.Fab")
			(hide yes)
			(effects
				(font
					(size 0.7 0.7)
					(thickness 0.15)
				)
				(justify left bottom mirror)
			)
		)
		(fp_text user "${REFERENCE}"
			(at -0.95 -3.168 0)
			(layer "B.Fab")
			(hide yes)
			(effects
				(font
					(size 0.7 0.7)
					(thickness 0.15)
				)
				(justify left bottom mirror)
			)
		)
		(fp_text user "Author: Antmicro"
			(at -0.95 -4.169 0)
			(layer "B.Fab")
			(hide yes)
			(effects
				(font
					(size 0.7 0.7)
					(thickness 0.15)
				)
				(justify left bottom mirror)
			)
		)
		(pad "1" smd roundrect
			(at -0.48 0 180)
			(size 0.59 0.64)
			(layers "B.Cu" "B.Paste" "B.Mask")
			(roundrect_rratio 0.25)
			(net 185 "/USB Debug, DP/FTDI_3V3")
			(pintype "passive")
		)
		(pad "2" smd roundrect
			(at 0.48 0 180)
			(size 0.59 0.64)
			(layers "B.Cu" "B.Paste" "B.Mask")
			(roundrect_rratio 0.25)
			(net 126 "Net-(U5-~{RESET})")
			(pintype "passive")
		)
	)
	(footprint "antmicro-footprints:SOT-23-6"
		(layer "B.Cu")
		(at 62.05 76.6 90)
		(property "Reference" "U37"
			(at 1.58 1.8 0)
			(layer "B.SilkS")
			(effects
				(font
					(size 0.7 0.7)
					(thickness 0.15)
				)
				(justify left bottom mirror)
			)
		)
		(property "Value" "74LVC2G14_SOT457"
			(at -1.75 -2.75 -90)
			(layer "B.Fab")
			(effects
				(font
					(size 0.7 0.7)
					(thickness 0.15)
				)
				(justify left bottom mirror)
			)
		)
		(property "Footprint" "antmicro-footprints:SOT-23-6"
			(at 0 0 90)
			(layer "B.Fab")
			(hide yes)
			(effects
				(font
					(size 1.27 1.27)
					(thickness 0.15)
				)
			)
		)
		(property "Datasheet" "https://assets.nexperia.com/documents/data-sheet/74LVC2G14.pdf"
			(at 0 0 90)
			(layer "B.Fab")
			(hide yes)
			(effects
				(font
					(size 1.27 1.27)
					(thickness 0.15)
				)
			)
		)
		(property "MPN" "74LVC2G14GV,125"
			(at 0 0 90)
			(unlocked yes)
			(layer "B.Fab")
			(hide yes)
			(effects
				(font
					(size 1 1)
					(thickness 0.15)
				)
				(justify mirror)
			)
		)
		(property "Manufacturer" "Nexperia"
			(at 0 0 90)
			(unlocked yes)
			(layer "B.Fab")
			(hide yes)
			(effects
				(font
					(size 1 1)
					(thickness 0.15)
				)
				(justify mirror)
			)
		)
		(property "Author" "Antmicro"
			(at 0 0 90)
			(unlocked yes)
			(layer "B.Fab")
			(hide yes)
			(effects
				(font
					(size 1 1)
					(thickness 0.15)
				)
				(justify mirror)
			)
		)
		(property "License" "Apache-2.0"
			(at 0 0 90)
			(unlocked yes)
			(layer "B.Fab")
			(hide yes)
			(effects
				(font
					(size 1 1)
					(thickness 0.15)
				)
				(justify mirror)
			)
		)
		(sheetname "Supply")
		(sheetfile "supply.kicad_sch")
		(attr smd)
		(fp_line
			(start 1.45 -0.643)
			(end 1.3 -0.643)
			(stroke
				(width 0.12)
				(type solid)
			)
			(layer "B.SilkS")
		)
		(fp_line
			(start 1.45 -0.343)
			(end 1.45 -0.643)
			(stroke
				(width 0.12)
				(type solid)
			)
			(layer "B.SilkS")
		)
		(fp_line
			(start -1.45 -0.343)
			(end -1.45 -0.643)
			(stroke
				(width 0.12)
				(type solid)
			)
			(layer "B.SilkS")
		)
		(fp_line
			(start 1.45 0.457)
			(end 1.45 0.757)
			(stroke
				(width 0.12)
				(type solid)
			)
			(layer "B.SilkS")
		)
		(fp_line
			(start -1.45 0.457)
			(end -1.45 0.757)
			(stroke
				(width 0.12)
				(type solid)
			)
			(layer "B.SilkS")
		)
		(fp_line
			(start 1.45 0.757)
			(end 1.3 0.757)
			(stroke
				(width 0.12)
				(type solid)
			)
			(layer "B.SilkS")
		)
		(fp_line
			(start -1.45 0.757)
			(end -1.3 0.757)
			(stroke
				(width 0.12)
				(type solid)
			)
			(layer "B.SilkS")
		)
		(fp_rect
			(start -1.55 1.85)
			(end 1.55 -1.75)
			(stroke
				(width 0.05)
				(type solid)
			)
			(fill none)
			(layer "B.CrtYd")
		)
		(fp_line
			(start 1.5 -0.643)
			(end 1.5 0.757)
			(stroke
				(width 0.1)
				(type solid)
			)
			(layer "B.Fab")
		)
		(fp_line
			(start -1.5 -0.643)
			(end 1.5 -0.643)
			(stroke
				(width 0.1)
				(type solid)
			)
			(layer "B.Fab")
		)
		(fp_line
			(start 1.5 0.757)
			(end -1.5 0.757)
			(stroke
				(width 0.1)
				(type solid)
			)
			(layer "B.Fab")
		)
		(fp_line
			(start -1.5 0.757)
			(end -1.5 -0.643)
			(stroke
				(width 0.1)
				(type solid)
			)
			(layer "B.Fab")
		)
		(fp_text user "."
			(at -1.62 -1.34 -90)
			(layer "B.SilkS")
			(effects
				(font
					(size 1 1)
					(thickness 0.15)
				)
				(justify mirror)
			)
		)
		(fp_text user "Author: Antmicro"
			(at -1.829 -5.25 -90)
			(layer "B.Fab")
			(hide yes)
			(effects
				(font
					(size 0.7 0.7)
					(thickness 0.15)
				)
				(justify left bottom mirror)
			)
		)
		(fp_text user "${REFERENCE}"
			(at -1.75 -4 -90)
			(layer "B.Fab")
			(hide yes)
			(effects
				(font
					(size 0.7 0.7)
					(thickness 0.15)
				)
				(justify left bottom mirror)
			)
		)
		(fp_text user "License: Apache-2.0"
			(at -1.75 -6.5 -90)
			(layer "B.Fab")
			(hide yes)
			(effects
				(font
					(size 0.7 0.7)
					(thickness 0.15)
				)
				(justify left bottom mirror)
			)
		)
		(pad "1" smd roundrect
			(at -0.954 -1.1 90)
			(size 0.55 1)
			(layers "B.Cu" "B.Paste" "B.Mask")
			(roundrect_rratio 0.15)
			(net 137 "Net-(D36-A)")
			(pintype "input")
		)
		(pad "2" smd roundrect
			(at -0.003 -1.1 90)
			(size 0.55 1)
			(layers "B.Cu" "B.Paste" "B.Mask")
			(roundrect_rratio 0.15)
			(net 1 "GND")
			(pinfunction "GND")
			(pintype "power_in")
		)
		(pad "3" smd roundrect
			(at 0.947 -1.1 90)
			(size 0.55 1)
			(layers "B.Cu" "B.Paste" "B.Mask")
			(roundrect_rratio 0.15)
			(net 174 "Net-(D36-C)")
			(pintype "input")
		)
		(pad "4" smd roundrect
			(at 0.947 1.214 90)
			(size 0.55 1)
			(layers "B.Cu" "B.Paste" "B.Mask")
			(roundrect_rratio 0.15)
			(net 628 "Net-(Q11-G)")
			(pintype "output")
		)
		(pad "5" smd roundrect
			(at -0.003 1.214 90)
			(size 0.55 1)
			(layers "B.Cu" "B.Paste" "B.Mask")
			(roundrect_rratio 0.15)
			(net 117 "3V3_STDB")
			(pinfunction "VCC")
			(pintype "power_in")
		)
		(pad "6" smd roundrect
			(at -0.954 1.214 90)
			(size 0.55 1)
			(layers "B.Cu" "B.Paste" "B.Mask")
			(roundrect_rratio 0.15)
			(net 688 "Net-(U38-CLK)")
			(pintype "output")
		)
	)
	(footprint "antmicro-footprints:XDFN-2_1x0.60mm"
		(layer "B.Cu")
		(at 115.7 71.1 180)
		(property "Reference" "D17"
			(at 1.67 -1.4 0)
			(layer "B.SilkS")
			(effects
				(font
					(size 0.7 0.7)
					(thickness 0.15)
				)
				(justify right bottom mirror)
			)
		)
		(property "Value" "TPD1E0B04_XDFN-2"
			(at 0 -1.5 0)
			(layer "B.Fab")
			(effects
				(font
					(size 0.7 0.7)
					(thickness 0.15)
				)
				(justify left bottom mirror)
			)
		)
		(property "Footprint" "antmicro-footprints:XDFN-2_1x0.60mm"
			(at 0 0 180)
			(layer "F.Fab")
			(hide yes)
			(effects
				(font
					(size 1.27 1.27)
					(thickness 0.15)
				)
			)
		)
		(property "Datasheet" "https://www.ti.com/general/docs/suppproductinfo.tsp?distId=26&gotoUrl=https://www.ti.com/lit/gpn/tpd1e0b04"
			(at 0 0 180)
			(layer "F.Fab")
			(hide yes)
			(effects
				(font
					(size 1.27 1.27)
					(thickness 0.15)
				)
			)
		)
		(property "MPN" "TPD1E0B04DPYR"
			(at 231.4 142.2 0)
			(layer "B.Fab")
			(hide yes)
			(effects
				(font
					(size 1 1)
					(thickness 0.15)
				)
				(justify mirror)
			)
		)
		(property "Manufacturer" "Texas Instruments"
			(at 231.4 142.2 0)
			(layer "B.Fab")
			(hide yes)
			(effects
				(font
					(size 1 1)
					(thickness 0.15)
				)
				(justify mirror)
			)
		)
		(property "Author" "Antmicro"
			(at 231.4 142.2 0)
			(layer "B.Fab")
			(hide yes)
			(effects
				(font
					(size 1 1)
					(thickness 0.15)
				)
				(justify mirror)
			)
		)
		(property "License" "Apache-2.0"
			(at 231.4 142.2 0)
			(layer "B.Fab")
			(hide yes)
			(effects
				(font
					(size 1 1)
					(thickness 0.15)
				)
				(justify mirror)
			)
		)
		(sheetname "Peripherals")
		(sheetfile "peripherals.kicad_sch")
		(attr smd)
		(fp_rect
			(start -0.725 0.475)
			(end 0.725 -0.475)
			(stroke
				(width 0.05)
				(type solid)
			)
			(fill none)
			(layer "B.CrtYd")
		)
		(fp_rect
			(start -0.55 0.35)
			(end 0.55 -0.35)
			(stroke
				(width 0.15)
				(type solid)
			)
			(fill none)
			(layer "B.Fab")
		)
		(fp_text user "${REFERENCE}"
			(at -0.8 -3.2 0)
			(layer "B.Fab")
			(hide yes)
			(effects
				(font
					(size 0.7 0.7)
					(thickness 0.15)
				)
				(justify left bottom mirror)
			)
		)
		(fp_text user "Author: Antmicro"
			(at -0.8 -4.4 0)
			(layer "B.Fab")
			(hide yes)
			(effects
				(font
					(size 0.7 0.7)
					(thickness 0.15)
				)
				(justify left bottom mirror)
			)
		)
		(fp_text user "License: Apache-2.0"
			(at -0.8 -5.6 0)
			(layer "B.Fab")
			(hide yes)
			(effects
				(font
					(size 0.7 0.7)
					(thickness 0.15)
				)
				(justify left bottom mirror)
			)
		)
		(pad "1" smd roundrect
			(at -0.351 0 180)
			(size 0.3 0.5)
			(layers "B.Cu" "B.Paste" "B.Mask")
			(roundrect_rratio 0.25)
			(net 114 "USBSS1_RX_P")
			(pinfunction "C")
			(pintype "passive")
		)
		(pad "2" smd roundrect
			(at 0.349 0 180)
			(size 0.3 0.5)
			(layers "B.Cu" "B.Paste" "B.Mask")
			(roundrect_rratio 0.25)
			(net 1 "GND")
			(pinfunction "A")
			(pintype "passive")
		)
	)
)
